(kicad_pcb
	(version 20260206)
	(generator "pcbnew")
	(generator_version "10.0")
	(general
		(thickness 1.6)
		(legacy_teardrops no)
	)
	(paper "A4")
	(title_block
		(title "01162023_DA0F0TEBIF0_F0T_Expander_BD_F_brd_V02_OCP.brd")
		(comment 1 "Grand Teton / footprints 7654-7662 of 9728")
	)
	(layers
		(0 "F.Cu" signal "TOP")
		(4 "In1.Cu" signal "GND")
		(6 "In2.Cu" signal "VCC")
		(8 "In3.Cu" signal "VCC1")
		(10 "In4.Cu" signal "GND1")
		(12 "In5.Cu" signal "IN1")
		(14 "In6.Cu" signal "GND2")
		(16 "In7.Cu" signal "IN2")
		(18 "In8.Cu" signal "GND3")
		(20 "In9.Cu" signal "IN3")
		(22 "In10.Cu" signal "GND4")
		(24 "In11.Cu" signal "IN4")
		(26 "In12.Cu" signal "GND5")
		(28 "In13.Cu" signal "IN5")
		(30 "In14.Cu" signal "GND6")
		(32 "In15.Cu" signal "IN6")
		(34 "In16.Cu" signal "GND7")
		(2 "B.Cu" signal "BOTTOM")
		(9 "F.Adhes" user "F.Adhesive")
		(11 "B.Adhes" user "B.Adhesive")
		(13 "F.Paste" user "Package Geometry/Pastemask Top")
		(15 "B.Paste" user "Package Geometry/Pastemask Bottom")
		(5 "F.SilkS" user "Ref Des/Silkscreen Top")
		(7 "B.SilkS" user "Ref Des/Silkscreen Bottom")
		(1 "F.Mask" user "Board Geometry/Soldermask Top")
		(3 "B.Mask" user "Board Geometry/Soldermask Bottom")
		(17 "Dwgs.User" user "User.Drawings")
		(19 "Cmts.User" user "User.Comments")
		(21 "Eco1.User" user "User.Eco1")
		(23 "Eco2.User" user "User.Eco2")
		(25 "Edge.Cuts" user "Board Geometry/Outline")
		(27 "Margin" user)
		(31 "F.CrtYd" user "Package Geometry/Place Bound Top")
		(29 "B.CrtYd" user "Package Geometry/Place Bound Bottom")
		(35 "F.Fab" user "Ref Des/Assembly Top")
		(33 "B.Fab" user "Ref Des/Assembly Bottom")
	)
	(footprint ""
		(layer "B.Cu")
		(at 226.19716 -266.873228 180)
		(property "Reference" "R6130"
			(at 0 0 0)
			(layer "B.SilkS")
			(hide yes)
			(effects
				(font
					(size 1.27 1.27)
				)
				(justify mirror)
			)
		)
		(property "Value" ""
			(at 0 0 0)
			(layer "B.Fab")
			(effects
				(font
					(size 1.27 1.27)
				)
				(justify mirror)
			)
		)
		(duplicate_pad_numbers_are_jumpers no)
		(fp_line
			(start 2.576322 1.1303)
			(end 2.576322 -1.1303)
			(stroke
				(width 0.1524)
				(type default)
			)
			(layer "B.SilkS")
		)
		(fp_line
			(start 2.576322 -1.1303)
			(end -2.576322 -1.1303)
			(stroke
				(width 0.1524)
				(type default)
			)
			(layer "B.SilkS")
		)
		(fp_line
			(start -2.576322 1.1303)
			(end 2.576322 1.1303)
			(stroke
				(width 0.1524)
				(type default)
			)
			(layer "B.SilkS")
		)
		(fp_line
			(start -2.576322 -1.1303)
			(end -2.576322 1.1303)
			(stroke
				(width 0.1524)
				(type default)
			)
			(layer "B.SilkS")
		)
		(fp_line
			(start 1.649984 0.899922)
			(end -1.649984 0.899922)
			(stroke
				(width 0.1)
				(type default)
			)
			(layer "B.Fab")
		)
		(fp_line
			(start 1.649984 -0.899922)
			(end 1.649984 0.899922)
			(stroke
				(width 0.1)
				(type default)
			)
			(layer "B.Fab")
		)
		(fp_line
			(start -1.649984 0.899922)
			(end -1.649984 -0.899922)
			(stroke
				(width 0.1)
				(type default)
			)
			(layer "B.Fab")
		)
		(fp_line
			(start -1.649984 -0.899922)
			(end 1.649984 -0.899922)
			(stroke
				(width 0.1)
				(type default)
			)
			(layer "B.Fab")
		)
		(pad "1A" smd rect
			(at 1.700022 0)
			(size 1.4986 2.0066)
			(layers "B.Cu" "B.Mask" "B.Paste")
			(net "P1V25_PEX1")
		)
		(pad "1B" smd rect
			(at 1.077722 0)
			(size 0.254 0.508)
			(layers "B.Cu" "B.Mask" "B.Paste")
			(net "P1V25_PEX1")
		)
		(pad "2A" smd rect
			(at -1.700022 0)
			(size 1.4986 2.0066)
			(layers "B.Cu" "B.Mask" "B.Paste")
			(net "P1V25_SERDES_VDDPLL_PEX1")
		)
		(pad "2B" smd rect
			(at -1.077722 0)
			(size 0.254 0.508)
			(layers "B.Cu" "B.Mask" "B.Paste")
			(net "P1V25_SERDES_VDDPLL_PEX1")
		)
	)
	(footprint ""
		(layer "B.Cu")
		(at 61.074808 -293.99992 90)
		(property "Reference" "C1135"
			(at 0 0 90)
			(layer "B.SilkS")
			(hide yes)
			(effects
				(font
					(size 1.27 1.27)
				)
				(justify mirror)
			)
		)
		(property "Value" ""
			(at 0 0 90)
			(layer "B.Fab")
			(effects
				(font
					(size 1.27 1.27)
				)
				(justify mirror)
			)
		)
		(duplicate_pad_numbers_are_jumpers no)
		(fp_line
			(start 0.299974 -0.150114)
			(end -0.299974 -0.150114)
			(stroke
				(width 0.1)
				(type default)
			)
			(layer "B.Fab")
		)
		(fp_line
			(start -0.299974 -0.150114)
			(end -0.299974 0.150114)
			(stroke
				(width 0.1)
				(type default)
			)
			(layer "B.Fab")
		)
		(fp_line
			(start 0.299974 0.150114)
			(end 0.299974 -0.150114)
			(stroke
				(width 0.1)
				(type default)
			)
			(layer "B.Fab")
		)
		(fp_line
			(start -0.299974 0.150114)
			(end 0.299974 0.150114)
			(stroke
				(width 0.1)
				(type default)
			)
			(layer "B.Fab")
		)
		(pad "1" smd rect
			(at 0.2667 0 270)
			(size 0.3048 0.381)
			(layers "B.Cu" "B.Mask" "B.Paste")
			(net "P0V8_PEX0")
		)
		(pad "2" smd rect
			(at -0.2667 0 270)
			(size 0.3048 0.381)
			(layers "B.Cu" "B.Mask" "B.Paste")
			(net "GND")
		)
	)
	(footprint ""
		(layer "B.Cu")
		(at 278.935942 -291.624766)
		(property "Reference" "C3407"
			(at 0 0 0)
			(layer "B.SilkS")
			(hide yes)
			(effects
				(font
					(size 1.27 1.27)
				)
				(justify mirror)
			)
		)
		(property "Value" ""
			(at 0 0 0)
			(layer "B.Fab")
			(effects
				(font
					(size 1.27 1.27)
				)
				(justify mirror)
			)
		)
		(duplicate_pad_numbers_are_jumpers no)
		(fp_line
			(start -0.299974 -0.150114)
			(end -0.299974 0.150114)
			(stroke
				(width 0.1)
				(type default)
			)
			(layer "B.Fab")
		)
		(fp_line
			(start -0.299974 0.150114)
			(end 0.299974 0.150114)
			(stroke
				(width 0.1)
				(type default)
			)
			(layer "B.Fab")
		)
		(fp_line
			(start 0.299974 -0.150114)
			(end -0.299974 -0.150114)
			(stroke
				(width 0.1)
				(type default)
			)
			(layer "B.Fab")
		)
		(fp_line
			(start 0.299974 0.150114)
			(end 0.299974 -0.150114)
			(stroke
				(width 0.1)
				(type default)
			)
			(layer "B.Fab")
		)
		(pad "1" smd rect
			(at 0.2667 0 180)
			(size 0.3048 0.381)
			(layers "B.Cu" "B.Mask" "B.Paste")
			(net "PCEPLL7_VDDA18_PEX2")
		)
		(pad "2" smd rect
			(at -0.2667 0 180)
			(size 0.3048 0.381)
			(layers "B.Cu" "B.Mask" "B.Paste")
			(net "GND")
		)
	)
	(footprint ""
		(layer "B.Cu")
		(at 406.049988 -303.499774 -90)
		(property "Reference" "C3430"
			(at 0 0 90)
			(layer "B.SilkS")
			(hide yes)
			(effects
				(font
					(size 1.27 1.27)
				)
				(justify mirror)
			)
		)
		(property "Value" ""
			(at 0 0 90)
			(layer "B.Fab")
			(effects
				(font
					(size 1.27 1.27)
				)
				(justify mirror)
			)
		)
		(duplicate_pad_numbers_are_jumpers no)
		(fp_line
			(start -0.299974 0.150114)
			(end 0.299974 0.150114)
			(stroke
				(width 0.1)
				(type default)
			)
			(layer "B.Fab")
		)
		(fp_line
			(start 0.299974 0.150114)
			(end 0.299974 -0.150114)
			(stroke
				(width 0.1)
				(type default)
			)
			(layer "B.Fab")
		)
		(fp_line
			(start -0.299974 -0.150114)
			(end -0.299974 0.150114)
			(stroke
				(width 0.1)
				(type default)
			)
			(layer "B.Fab")
		)
		(fp_line
			(start 0.299974 -0.150114)
			(end -0.299974 -0.150114)
			(stroke
				(width 0.1)
				(type default)
			)
			(layer "B.Fab")
		)
		(pad "1" smd rect
			(at 0.2667 0 90)
			(size 0.3048 0.381)
			(layers "B.Cu" "B.Mask" "B.Paste")
			(net "P1V25_PEX3")
		)
		(pad "2" smd rect
			(at -0.2667 0 90)
			(size 0.3048 0.381)
			(layers "B.Cu" "B.Mask" "B.Paste")
			(net "GND")
		)
	)
	(footprint ""
		(layer "B.Cu")
		(at 162.4457 -292.57498)
		(property "Reference" "C3230"
			(at 0 0 0)
			(layer "B.SilkS")
			(hide yes)
			(effects
				(font
					(size 1.27 1.27)
				)
				(justify mirror)
			)
		)
		(property "Value" ""
			(at 0 0 0)
			(layer "B.Fab")
			(effects
				(font
					(size 1.27 1.27)
				)
				(justify mirror)
			)
		)
		(duplicate_pad_numbers_are_jumpers no)
		(fp_line
			(start -0.299974 -0.150114)
			(end -0.299974 0.150114)
			(stroke
				(width 0.1)
				(type default)
			)
			(layer "B.Fab")
		)
		(fp_line
			(start -0.299974 0.150114)
			(end 0.299974 0.150114)
			(stroke
				(width 0.1)
				(type default)
			)
			(layer "B.Fab")
		)
		(fp_line
			(start 0.299974 -0.150114)
			(end -0.299974 -0.150114)
			(stroke
				(width 0.1)
				(type default)
			)
			(layer "B.Fab")
		)
		(fp_line
			(start 0.299974 0.150114)
			(end 0.299974 -0.150114)
			(stroke
				(width 0.1)
				(type default)
			)
			(layer "B.Fab")
		)
		(pad "1" smd rect
			(at 0.2667 0 180)
			(size 0.3048 0.381)
			(layers "B.Cu" "B.Mask" "B.Paste")
			(net "PCEPLL6_VDDA18_PEX1")
		)
		(pad "2" smd rect
			(at -0.2667 0 180)
			(size 0.3048 0.381)
			(layers "B.Cu" "B.Mask" "B.Paste")
			(net "GND")
		)
	)
	(footprint ""
		(layer "B.Cu")
		(at 343.694004 -218.787218 -90)
		(property "Reference" "C2062"
			(at 0 0 90)
			(layer "B.SilkS")
			(hide yes)
			(effects
				(font
					(size 1.27 1.27)
				)
				(justify mirror)
			)
		)
		(property "Value" ""
			(at 0 0 90)
			(layer "B.Fab")
			(effects
				(font
					(size 1.27 1.27)
				)
				(justify mirror)
			)
		)
		(duplicate_pad_numbers_are_jumpers no)
		(fp_line
			(start -0.69215 0.2921)
			(end 0.69215 0.2921)
			(stroke
				(width 0.1524)
				(type default)
			)
			(layer "B.SilkS")
		)
		(fp_line
			(start 0.69215 0.2921)
			(end 0.69215 -0.2921)
			(stroke
				(width 0.1524)
				(type default)
			)
			(layer "B.SilkS")
		)
		(fp_line
			(start -0.69215 -0.2921)
			(end -0.69215 0.2921)
			(stroke
				(width 0.1524)
				(type default)
			)
			(layer "B.SilkS")
		)
		(fp_line
			(start 0.69215 -0.2921)
			(end -0.69215 -0.2921)
			(stroke
				(width 0.1524)
				(type default)
			)
			(layer "B.SilkS")
		)
		(fp_line
			(start -0.51435 0.2794)
			(end 0.51435 0.2794)
			(stroke
				(width 0.1)
				(type default)
			)
			(layer "B.Fab")
		)
		(fp_line
			(start 0.51435 0.2794)
			(end 0.51435 -0.2794)
			(stroke
				(width 0.1)
				(type default)
			)
			(layer "B.Fab")
		)
		(fp_line
			(start -0.51435 -0.2794)
			(end -0.51435 0.2794)
			(stroke
				(width 0.1)
				(type default)
			)
			(layer "B.Fab")
		)
		(fp_line
			(start 0.51435 -0.2794)
			(end -0.51435 -0.2794)
			(stroke
				(width 0.1)
				(type default)
			)
			(layer "B.Fab")
		)
		(pad "1" smd circle
			(at 0.40005 0 90)
			(size 0 0)
			(layers "B.Cu" "B.Mask" "B.Paste")
			(net "P3V3_VCC_FPGA_CORE")
		)
		(pad "2" smd circle
			(at -0.40005 0 90)
			(size 0 0)
			(layers "B.Cu" "B.Mask" "B.Paste")
			(net "GND")
		)
		(zone
			(layer "B.Cu")
			(hatch none 0.5)
			(connect_pads
				(clearance 0)
			)
			(min_thickness 0.25)
			(keepout
				(tracks not_allowed)
				(vias allowed)
				(pads allowed)
				(copperpour not_allowed)
				(footprints allowed)
			)
			(placement
				(enabled no)
				(sheetname "")
			)
			(fill
				(thermal_gap 0.5)
				(thermal_bridge_width 0.5)
				(island_removal_mode 0)
			)
			(polygon
				(pts
					(xy 343.606374 -218.596718) (xy 343.548208 -218.688158) (xy 343.548208 -218.887548) (xy 343.606374 -218.977718)
					(xy 343.781634 -218.977718) (xy 343.840054 -218.887548) (xy 343.840054 -218.688158) (xy 343.781888 -218.596718)
				)
			)
		)
	)
	(footprint ""
		(layer "B.Cu")
		(at 295.706038 -202.16114 90)
		(property "Reference" "R1038"
			(at 0 0 90)
			(layer "B.SilkS")
			(hide yes)
			(effects
				(font
					(size 1.27 1.27)
				)
				(justify mirror)
			)
		)
		(property "Value" ""
			(at 0 0 90)
			(layer "B.Fab")
			(effects
				(font
					(size 1.27 1.27)
				)
				(justify mirror)
			)
		)
		(duplicate_pad_numbers_are_jumpers no)
		(fp_line
			(start 0.7874 -0.4064)
			(end -0.7874 -0.4064)
			(stroke
				(width 0.1524)
				(type default)
			)
			(layer "B.SilkS")
		)
		(fp_line
			(start -0.7874 -0.4064)
			(end -0.7874 0.4064)
			(stroke
				(width 0.1524)
				(type default)
			)
			(layer "B.SilkS")
		)
		(fp_line
			(start 0.7874 0.4064)
			(end 0.7874 -0.4064)
			(stroke
				(width 0.1524)
				(type default)
			)
			(layer "B.SilkS")
		)
		(fp_line
			(start -0.7874 0.4064)
			(end 0.7874 0.4064)
			(stroke
				(width 0.1524)
				(type default)
			)
			(layer "B.SilkS")
		)
		(fp_line
			(start 0.67945 -0.305054)
			(end 0.12065 -0.305054)
			(stroke
				(width 0.1)
				(type default)
			)
			(layer "B.Fab")
		)
		(fp_line
			(start 0.12065 -0.305054)
			(end 0.12065 -0.2794)
			(stroke
				(width 0.1)
				(type default)
			)
			(layer "B.Fab")
		)
		(fp_line
			(start -0.12065 -0.3048)
			(end -0.67945 -0.3048)
			(stroke
				(width 0.1)
				(type default)
			)
			(layer "B.Fab")
		)
		(fp_line
			(start -0.67945 -0.3048)
			(end -0.67945 0.3048)
			(stroke
				(width 0.1)
				(type default)
			)
			(layer "B.Fab")
		)
		(fp_line
			(start 0.12065 -0.2794)
			(end -0.12065 -0.2794)
			(stroke
				(width 0.1)
				(type default)
			)
			(layer "B.Fab")
		)
		(fp_line
			(start -0.12065 -0.2794)
			(end -0.12065 -0.3048)
			(stroke
				(width 0.1)
				(type default)
			)
			(layer "B.Fab")
		)
		(fp_line
			(start 0.12065 0.2794)
			(end 0.12065 0.3048)
			(stroke
				(width 0.1)
				(type default)
			)
			(layer "B.Fab")
		)
		(fp_line
			(start -0.120396 0.2794)
			(end 0.12065 0.2794)
			(stroke
				(width 0.1)
				(type default)
			)
			(layer "B.Fab")
		)
		(fp_line
			(start 0.67945 0.3048)
			(end 0.67945 -0.305054)
			(stroke
				(width 0.1)
				(type default)
			)
			(layer "B.Fab")
		)
		(fp_line
			(start 0.12065 0.3048)
			(end 0.67945 0.3048)
			(stroke
				(width 0.1)
				(type default)
			)
			(layer "B.Fab")
		)
		(fp_line
			(start -0.120396 0.3048)
			(end -0.120396 0.2794)
			(stroke
				(width 0.1)
				(type default)
			)
			(layer "B.Fab")
		)
		(fp_line
			(start -0.67945 0.3048)
			(end -0.120396 0.3048)
			(stroke
				(width 0.1)
				(type default)
			)
			(layer "B.Fab")
		)
		(pad "1" smd circle
			(at 0.40005 0 270)
			(size 0 0)
			(layers "B.Cu" "B.Mask" "B.Paste")
			(net "SPI_BIC1_CLK_LS23_DIR2")
		)
		(pad "2" smd circle
			(at -0.40005 0 270)
			(size 0 0)
			(layers "B.Cu" "B.Mask" "B.Paste")
			(net "P1V8_PEX")
		)
	)
	(footprint ""
		(layer "B.Cu")
		(at 44.449746 -294.94988)
		(property "Reference" "C3005"
			(at 0 0 0)
			(layer "B.SilkS")
			(hide yes)
			(effects
				(font
					(size 1.27 1.27)
				)
				(justify mirror)
			)
		)
		(property "Value" ""
			(at 0 0 0)
			(layer "B.Fab")
			(effects
				(font
					(size 1.27 1.27)
				)
				(justify mirror)
			)
		)
		(duplicate_pad_numbers_are_jumpers no)
		(fp_line
			(start -0.299974 -0.150114)
			(end -0.299974 0.150114)
			(stroke
				(width 0.1)
				(type default)
			)
			(layer "B.Fab")
		)
		(fp_line
			(start -0.299974 0.150114)
			(end 0.299974 0.150114)
			(stroke
				(width 0.1)
				(type default)
			)
			(layer "B.Fab")
		)
		(fp_line
			(start 0.299974 -0.150114)
			(end -0.299974 -0.150114)
			(stroke
				(width 0.1)
				(type default)
			)
			(layer "B.Fab")
		)
		(fp_line
			(start 0.299974 0.150114)
			(end 0.299974 -0.150114)
			(stroke
				(width 0.1)
				(type default)
			)
			(layer "B.Fab")
		)
		(pad "1" smd rect
			(at 0.2667 0 180)
			(size 0.3048 0.381)
			(layers "B.Cu" "B.Mask" "B.Paste")
			(net "P1V8_PEX")
		)
		(pad "2" smd rect
			(at -0.2667 0 180)
			(size 0.3048 0.381)
			(layers "B.Cu" "B.Mask" "B.Paste")
			(net "GND")
		)
	)
	(footprint ""
		(layer "B.Cu")
		(at 334.489044 -213.593934)
		(property "Reference" "C2075"
			(at 0 0 0)
			(layer "B.SilkS")
			(hide yes)
			(effects
				(font
					(size 1.27 1.27)
				)
				(justify mirror)
			)
		)
		(property "Value" ""
			(at 0 0 0)
			(layer "B.Fab")
			(effects
				(font
					(size 1.27 1.27)
				)
				(justify mirror)
			)
		)
		(duplicate_pad_numbers_are_jumpers no)
		(fp_line
			(start -0.69215 -0.2921)
			(end -0.69215 0.2921)
			(stroke
				(width 0.1524)
				(type default)
			)
			(layer "B.SilkS")
		)
		(fp_line
			(start -0.69215 0.2921)
			(end 0.69215 0.2921)
			(stroke
				(width 0.1524)
				(type default)
			)
			(layer "B.SilkS")
		)
		(fp_line
			(start 0.69215 -0.2921)
			(end -0.69215 -0.2921)
			(stroke
				(width 0.1524)
				(type default)
			)
			(layer "B.SilkS")
		)
		(fp_line
			(start 0.69215 0.2921)
			(end 0.69215 -0.2921)
			(stroke
				(width 0.1524)
				(type default)
			)
			(layer "B.SilkS")
		)
		(fp_line
			(start -0.51435 -0.2794)
			(end -0.51435 0.2794)
			(stroke
				(width 0.1)
				(type default)
			)
			(layer "B.Fab")
		)
		(fp_line
			(start -0.51435 0.2794)
			(end 0.51435 0.2794)
			(stroke
				(width 0.1)
				(type default)
			)
			(layer "B.Fab")
		)
		(fp_line
			(start 0.51435 -0.2794)
			(end -0.51435 -0.2794)
			(stroke
				(width 0.1)
				(type default)
			)
			(layer "B.Fab")
		)
		(fp_line
			(start 0.51435 0.2794)
			(end 0.51435 -0.2794)
			(stroke
				(width 0.1)
				(type default)
			)
			(layer "B.Fab")
		)
		(pad "1" smd circle
			(at 0.40005 0 180)
			(size 0 0)
			(layers "B.Cu" "B.Mask" "B.Paste")
			(net "P3V3_FPGA_VCCIO3")
		)
		(pad "2" smd circle
			(at -0.40005 0 180)
			(size 0 0)
			(layers "B.Cu" "B.Mask" "B.Paste")
			(net "GND")
		)
		(zone
			(layer "B.Cu")
			(hatch none 0.5)
			(connect_pads
				(clearance 0)
			)
			(min_thickness 0.25)
			(keepout
				(tracks not_allowed)
				(vias allowed)
				(pads allowed)
				(copperpour not_allowed)
				(footprints allowed)
			)
			(placement
				(enabled no)
				(sheetname "")
			)
			(fill
				(thermal_gap 0.5)
				(thermal_bridge_width 0.5)
				(island_removal_mode 0)
			)
			(polygon
				(pts
					(xy 334.679544 -213.506304) (xy 334.588104 -213.448138) (xy 334.388714 -213.448138) (xy 334.298544 -213.506304)
					(xy 334.298544 -213.681564) (xy 334.388714 -213.739984) (xy 334.588104 -213.739984) (xy 334.679544 -213.681818)
				)
			)
		)
	)
)
